(kicad_pcb
	(version 20260206)
	(generator "pcbnew")
	(generator_version "10.0")
	(general
		(thickness 1.6)
		(legacy_teardrops no)
	)
	(paper "A4")
	(title_block
		(title "pdpb — Lightning_PDPB_BRD.brd")
		(comment 1 "Lightning (Wiwynn / Facebook NVMe JBOF) / footprints 101-107 of 1140")
	)
	(layers
		(0 "F.Cu" signal "TOP")
		(4 "In1.Cu" signal "L2GND")
		(6 "In2.Cu" signal "L3")
		(8 "In3.Cu" signal "L4VCC")
		(10 "In4.Cu" signal "L5VCC")
		(12 "In5.Cu" signal "L6")
		(14 "In6.Cu" signal "L7GND")
		(2 "B.Cu" signal "BOTTOM")
		(9 "F.Adhes" user "F.Adhesive")
		(11 "B.Adhes" user "B.Adhesive")
		(13 "F.Paste" user "Package Geometry/Pastemask Top")
		(15 "B.Paste" user "Package Geometry/Pastemask Bottom")
		(5 "F.SilkS" user "Ref Des/Silkscreen Top")
		(7 "B.SilkS" user "Ref Des/Silkscreen Bottom")
		(1 "F.Mask" user "Board Geometry/Soldermask Top")
		(3 "B.Mask" user "Board Geometry/Soldermask Bottom")
		(17 "Dwgs.User" user "User.Drawings")
		(19 "Cmts.User" user "User.Comments")
		(21 "Eco1.User" user "User.Eco1")
		(23 "Eco2.User" user "User.Eco2")
		(25 "Edge.Cuts" user "Board Geometry/Outline")
		(27 "Margin" user)
		(31 "F.CrtYd" user "Package Geometry/Place Bound Top")
		(29 "B.CrtYd" user "Package Geometry/Place Bound Bottom")
		(35 "F.Fab" user "Ref Des/Assembly Top")
		(33 "B.Fab" user "Ref Des/Assembly Bottom")
	)
	(footprint ""
		(layer "F.Cu")
		(at 108.966 -436.88)
		(property "Reference" "R119"
			(at 0 0 0)
			(layer "F.SilkS")
			(hide yes)
			(effects
				(font
					(size 1.27 1.27)
				)
			)
		)
		(property "Value" "4K7R2J-2-GP"
			(at 0.064008 -3.993896 0)
			(unlocked yes)
			(layer "F.Fab")
			(hide yes)
			(effects
				(font
					(size 1.016 1.016)
					(thickness 0.1524)
				)
			)
		)
		(property "Device Type" "R402H16"
			(at 0.064008 -5.517896 0)
			(unlocked yes)
			(layer "F.Fab")
			(hide yes)
			(effects
				(font
					(size 1.016 1.016)
					(thickness 0.1524)
				)
			)
		)
		(duplicate_pad_numbers_are_jumpers no)
		(fp_line
			(start -0.508 -0.9398)
			(end -0.508 0.9398)
			(stroke
				(width 0.1524)
				(type default)
			)
			(layer "F.SilkS")
		)
		(fp_line
			(start 0.508 -0.9398)
			(end -0.508 -0.9398)
			(stroke
				(width 0.1524)
				(type default)
			)
			(layer "F.SilkS")
		)
		(fp_rect
			(start -0.508 0.9398)
			(end 0.508 -0.9398)
			(stroke
				(width 0)
				(type default)
			)
			(fill no)
			(layer "F.CrtYd")
		)
		(fp_rect
			(start -0.508 0.9398)
			(end 0.508 -0.9398)
			(stroke
				(width 0)
				(type default)
			)
			(fill no)
			(layer "F.Fab")
		)
		(pad "1" smd custom
			(at 0 -0.4445)
			(size 0.1397 0.1397)
			(layers "F.Cu" "F.Mask" "F.Paste")
			(net "P3V3")
			(options
				(clearance outline)
				(anchor circle)
			)
			(primitives
				(gr_poly
					(pts
						(arc
							(start -0.1778 -0.2794)
							(mid -0.249642 -0.249642)
							(end -0.2794 -0.1778)
						)
						(arc
							(start -0.2794 0.1778)
							(mid -0.249642 0.249642)
							(end -0.1778 0.2794)
						)
						(arc
							(start 0.1778 0.2794)
							(mid 0.249642 0.249642)
							(end 0.2794 0.1778)
						)
						(arc
							(start 0.2794 -0.1778)
							(mid 0.249642 -0.249642)
							(end 0.1778 -0.2794)
						)
					)
					(width 0)
					(fill yes)
				)
			)
		)
		(pad "2" smd custom
			(at 0 0.4445)
			(size 0.1397 0.1397)
			(layers "F.Cu" "F.Mask" "F.Paste")
			(net "SSD0_CLK0_OE_N")
			(options
				(clearance outline)
				(anchor circle)
			)
			(primitives
				(gr_poly
					(pts
						(arc
							(start -0.1778 -0.2794)
							(mid -0.249642 -0.249642)
							(end -0.2794 -0.1778)
						)
						(arc
							(start -0.2794 0.1778)
							(mid -0.249642 0.249642)
							(end -0.1778 0.2794)
						)
						(arc
							(start 0.1778 0.2794)
							(mid 0.249642 0.249642)
							(end 0.2794 0.1778)
						)
						(arc
							(start 0.2794 -0.1778)
							(mid 0.249642 -0.249642)
							(end 0.1778 -0.2794)
						)
					)
					(width 0)
					(fill yes)
				)
			)
		)
	)
	(footprint ""
		(layer "F.Cu")
		(at 87.757 -222.885 -90)
		(property "Reference" "C9372"
			(at 0 0 270)
			(layer "F.SilkS")
			(hide yes)
			(effects
				(font
					(size 1.27 1.27)
				)
			)
		)
		(property "Value" "SC1KP50V2KX-1GP"
			(at 1.1811 -2.7051 270)
			(unlocked yes)
			(layer "F.Fab")
			(hide yes)
			(effects
				(font
					(size 1.016 1.016)
					(thickness 0.1524)
				)
			)
		)
		(property "Device Type" "C402H22"
			(at 1.1811 -4.2291 270)
			(unlocked yes)
			(layer "F.Fab")
			(hide yes)
			(effects
				(font
					(size 1.016 1.016)
					(thickness 0.1524)
				)
			)
		)
		(duplicate_pad_numbers_are_jumpers no)
		(fp_rect
			(start -0.4318 0.9525)
			(end 0.4318 -0.9525)
			(stroke
				(width 0)
				(type default)
			)
			(fill no)
			(layer "F.CrtYd")
		)
		(fp_rect
			(start -0.4318 0.9525)
			(end 0.4318 -0.9525)
			(stroke
				(width 0)
				(type default)
			)
			(fill no)
			(layer "F.Fab")
		)
		(pad "1" smd custom
			(at 0 -0.4445 270)
			(size 0.1524 0.1524)
			(layers "F.Cu" "F.Mask" "F.Paste")
			(net "SSD12_CLK0_OE_R_N")
			(options
				(clearance outline)
				(anchor circle)
			)
			(primitives
				(gr_poly
					(pts
						(arc
							(start 0.3048 -0.2032)
							(mid 0.275042 -0.275042)
							(end 0.2032 -0.3048)
						)
						(arc
							(start -0.2032 -0.3048)
							(mid -0.275042 -0.275042)
							(end -0.3048 -0.2032)
						)
						(arc
							(start -0.3048 0.2032)
							(mid -0.275042 0.275042)
							(end -0.2032 0.3048)
						)
						(arc
							(start 0.2032 0.3048)
							(mid 0.275042 0.275042)
							(end 0.3048 0.2032)
						)
					)
					(width 0)
					(fill yes)
				)
			)
		)
		(pad "2" smd custom
			(at 0 0.4445 270)
			(size 0.1524 0.1524)
			(layers "F.Cu" "F.Mask" "F.Paste")
			(net "GND")
			(options
				(clearance outline)
				(anchor circle)
			)
			(primitives
				(gr_poly
					(pts
						(arc
							(start 0.3048 -0.2032)
							(mid 0.275042 -0.275042)
							(end 0.2032 -0.3048)
						)
						(arc
							(start -0.2032 -0.3048)
							(mid -0.275042 -0.275042)
							(end -0.3048 -0.2032)
						)
						(arc
							(start -0.3048 0.2032)
							(mid -0.275042 0.275042)
							(end -0.2032 0.3048)
						)
						(arc
							(start 0.2032 0.3048)
							(mid 0.275042 0.275042)
							(end 0.3048 0.2032)
						)
					)
					(width 0)
					(fill yes)
				)
			)
		)
	)
	(footprint ""
		(layer "F.Cu")
		(at 96.52 -313.817 180)
		(property "Reference" "R9097"
			(at 0 0 180)
			(layer "F.SilkS")
			(hide yes)
			(effects
				(font
					(size 1.27 1.27)
				)
			)
		)
		(property "Value" "27R2F-GP"
			(at 0.064008 -3.993896 180)
			(unlocked yes)
			(layer "F.Fab")
			(hide yes)
			(effects
				(font
					(size 1.016 1.016)
					(thickness 0.1524)
				)
			)
		)
		(property "Device Type" "R402H16"
			(at 0.064008 -5.517896 180)
			(unlocked yes)
			(layer "F.Fab")
			(hide yes)
			(effects
				(font
					(size 1.016 1.016)
					(thickness 0.1524)
				)
			)
		)
		(duplicate_pad_numbers_are_jumpers no)
		(fp_line
			(start 0.508 -0.9398)
			(end -0.508 -0.9398)
			(stroke
				(width 0.1524)
				(type default)
			)
			(layer "F.SilkS")
		)
		(fp_line
			(start -0.508 -0.9398)
			(end -0.508 0.9398)
			(stroke
				(width 0.1524)
				(type default)
			)
			(layer "F.SilkS")
		)
		(fp_rect
			(start -0.508 0.9398)
			(end 0.508 -0.9398)
			(stroke
				(width 0)
				(type default)
			)
			(fill no)
			(layer "F.CrtYd")
		)
		(fp_rect
			(start -0.508 0.9398)
			(end 0.508 -0.9398)
			(stroke
				(width 0)
				(type default)
			)
			(fill no)
			(layer "F.Fab")
		)
		(pad "1" smd custom
			(at 0 -0.4445 180)
			(size 0.1397 0.1397)
			(layers "F.Cu" "F.Mask" "F.Paste")
			(net "PE_CLK_100M_DR6_1_R_P")
			(options
				(clearance outline)
				(anchor circle)
			)
			(primitives
				(gr_poly
					(pts
						(arc
							(start -0.1778 -0.2794)
							(mid -0.249642 -0.249642)
							(end -0.2794 -0.1778)
						)
						(arc
							(start -0.2794 0.1778)
							(mid -0.249642 0.249642)
							(end -0.1778 0.2794)
						)
						(arc
							(start 0.1778 0.2794)
							(mid 0.249642 0.249642)
							(end 0.2794 0.1778)
						)
						(arc
							(start 0.2794 -0.1778)
							(mid 0.249642 -0.249642)
							(end 0.1778 -0.2794)
						)
					)
					(width 0)
					(fill yes)
				)
			)
		)
		(pad "2" smd custom
			(at 0 0.4445 180)
			(size 0.1397 0.1397)
			(layers "F.Cu" "F.Mask" "F.Paste")
			(net "PE_CLK100M_DR6_1_P")
			(options
				(clearance outline)
				(anchor circle)
			)
			(primitives
				(gr_poly
					(pts
						(arc
							(start -0.1778 -0.2794)
							(mid -0.249642 -0.249642)
							(end -0.2794 -0.1778)
						)
						(arc
							(start -0.2794 0.1778)
							(mid -0.249642 0.249642)
							(end -0.1778 0.2794)
						)
						(arc
							(start 0.1778 0.2794)
							(mid 0.249642 0.249642)
							(end 0.2794 0.1778)
						)
						(arc
							(start 0.2794 -0.1778)
							(mid 0.249642 -0.249642)
							(end 0.1778 -0.2794)
						)
					)
					(width 0)
					(fill yes)
				)
			)
		)
	)
	(footprint ""
		(layer "F.Cu")
		(at 99.06 -290.195 -90)
		(property "Reference" "R9488"
			(at 0 0 270)
			(layer "F.SilkS")
			(hide yes)
			(effects
				(font
					(size 1.27 1.27)
				)
			)
		)
		(property "Value" "4K7R2J-2-GP"
			(at 0.064008 -3.993896 270)
			(unlocked yes)
			(layer "F.Fab")
			(hide yes)
			(effects
				(font
					(size 1.016 1.016)
					(thickness 0.1524)
				)
			)
		)
		(property "Device Type" "R402H16"
			(at 0.064008 -5.517896 270)
			(unlocked yes)
			(layer "F.Fab")
			(hide yes)
			(effects
				(font
					(size 1.016 1.016)
					(thickness 0.1524)
				)
			)
		)
		(duplicate_pad_numbers_are_jumpers no)
		(fp_line
			(start -0.508 -0.9398)
			(end -0.508 0.9398)
			(stroke
				(width 0.1524)
				(type default)
			)
			(layer "F.SilkS")
		)
		(fp_line
			(start 0.508 -0.9398)
			(end -0.508 -0.9398)
			(stroke
				(width 0.1524)
				(type default)
			)
			(layer "F.SilkS")
		)
		(fp_rect
			(start -0.508 0.9398)
			(end 0.508 -0.9398)
			(stroke
				(width 0)
				(type default)
			)
			(fill no)
			(layer "F.CrtYd")
		)
		(fp_rect
			(start -0.508 0.9398)
			(end 0.508 -0.9398)
			(stroke
				(width 0)
				(type default)
			)
			(fill no)
			(layer "F.Fab")
		)
		(pad "1" smd custom
			(at 0 -0.4445 270)
			(size 0.1397 0.1397)
			(layers "F.Cu" "F.Mask" "F.Paste")
			(net "P3V3")
			(options
				(clearance outline)
				(anchor circle)
			)
			(primitives
				(gr_poly
					(pts
						(arc
							(start -0.1778 -0.2794)
							(mid -0.249642 -0.249642)
							(end -0.2794 -0.1778)
						)
						(arc
							(start -0.2794 0.1778)
							(mid -0.249642 0.249642)
							(end -0.1778 0.2794)
						)
						(arc
							(start 0.1778 0.2794)
							(mid 0.249642 0.249642)
							(end 0.2794 0.1778)
						)
						(arc
							(start 0.2794 -0.1778)
							(mid 0.249642 -0.249642)
							(end 0.1778 -0.2794)
						)
					)
					(width 0)
					(fill yes)
				)
			)
		)
		(pad "2" smd custom
			(at 0 0.4445 270)
			(size 0.1397 0.1397)
			(layers "F.Cu" "F.Mask" "F.Paste")
			(net "SSD2_CLK0_OE_N")
			(options
				(clearance outline)
				(anchor circle)
			)
			(primitives
				(gr_poly
					(pts
						(arc
							(start -0.1778 -0.2794)
							(mid -0.249642 -0.249642)
							(end -0.2794 -0.1778)
						)
						(arc
							(start -0.2794 0.1778)
							(mid -0.249642 0.249642)
							(end -0.1778 0.2794)
						)
						(arc
							(start 0.1778 0.2794)
							(mid 0.249642 0.249642)
							(end 0.2794 0.1778)
						)
						(arc
							(start 0.2794 -0.1778)
							(mid 0.249642 -0.249642)
							(end 0.1778 -0.2794)
						)
					)
					(width 0)
					(fill yes)
				)
			)
		)
	)
	(footprint ""
		(layer "F.Cu")
		(at 78.5622 -100.2792 180)
		(property "Reference" "R9972"
			(at 0 0 180)
			(layer "F.SilkS")
			(hide yes)
			(effects
				(font
					(size 1.27 1.27)
				)
			)
		)
		(property "Value" "470R2F-GP"
			(at 0.064008 -3.993896 180)
			(unlocked yes)
			(layer "F.Fab")
			(hide yes)
			(effects
				(font
					(size 1.016 1.016)
					(thickness 0.1524)
				)
			)
		)
		(property "Device Type" "R402H16"
			(at 0.064008 -5.517896 180)
			(unlocked yes)
			(layer "F.Fab")
			(hide yes)
			(effects
				(font
					(size 1.016 1.016)
					(thickness 0.1524)
				)
			)
		)
		(duplicate_pad_numbers_are_jumpers no)
		(fp_line
			(start 0.508 -0.9398)
			(end -0.508 -0.9398)
			(stroke
				(width 0.1524)
				(type default)
			)
			(layer "F.SilkS")
		)
		(fp_line
			(start -0.508 -0.9398)
			(end -0.508 0.9398)
			(stroke
				(width 0.1524)
				(type default)
			)
			(layer "F.SilkS")
		)
		(fp_rect
			(start -0.508 0.9398)
			(end 0.508 -0.9398)
			(stroke
				(width 0)
				(type default)
			)
			(fill no)
			(layer "F.CrtYd")
		)
		(fp_rect
			(start -0.508 0.9398)
			(end 0.508 -0.9398)
			(stroke
				(width 0)
				(type default)
			)
			(fill no)
			(layer "F.Fab")
		)
		(pad "1" smd custom
			(at 0 -0.4445 180)
			(size 0.1397 0.1397)
			(layers "F.Cu" "F.Mask" "F.Paste")
			(net "VDD_DIFF_4")
			(options
				(clearance outline)
				(anchor circle)
			)
			(primitives
				(gr_poly
					(pts
						(arc
							(start -0.1778 -0.2794)
							(mid -0.249642 -0.249642)
							(end -0.2794 -0.1778)
						)
						(arc
							(start -0.2794 0.1778)
							(mid -0.249642 0.249642)
							(end -0.1778 0.2794)
						)
						(arc
							(start 0.1778 0.2794)
							(mid 0.249642 0.249642)
							(end 0.2794 0.1778)
						)
						(arc
							(start 0.2794 -0.1778)
							(mid 0.249642 -0.249642)
							(end 0.1778 -0.2794)
						)
					)
					(width 0)
					(fill yes)
				)
			)
		)
		(pad "2" smd custom
			(at 0 0.4445 180)
			(size 0.1397 0.1397)
			(layers "F.Cu" "F.Mask" "F.Paste")
			(net "PE_100M_CLK1_N")
			(options
				(clearance outline)
				(anchor circle)
			)
			(primitives
				(gr_poly
					(pts
						(arc
							(start -0.1778 -0.2794)
							(mid -0.249642 -0.249642)
							(end -0.2794 -0.1778)
						)
						(arc
							(start -0.2794 0.1778)
							(mid -0.249642 0.249642)
							(end -0.1778 0.2794)
						)
						(arc
							(start 0.1778 0.2794)
							(mid 0.249642 0.249642)
							(end 0.2794 0.1778)
						)
						(arc
							(start 0.2794 -0.1778)
							(mid 0.249642 -0.249642)
							(end 0.1778 -0.2794)
						)
					)
					(width 0)
					(fill yes)
				)
			)
		)
	)
	(footprint ""
		(layer "F.Cu")
		(at 18.23974 -466.66658 -90)
		(property "Reference" "R9947"
			(at 0 0 270)
			(layer "F.SilkS")
			(hide yes)
			(effects
				(font
					(size 1.27 1.27)
				)
			)
		)
		(property "Value" "4K7R2J-2-GP"
			(at 0.064008 -3.993896 270)
			(unlocked yes)
			(layer "F.Fab")
			(hide yes)
			(effects
				(font
					(size 1.016 1.016)
					(thickness 0.1524)
				)
			)
		)
		(property "Device Type" "R402H16"
			(at 0.064008 -5.517896 270)
			(unlocked yes)
			(layer "F.Fab")
			(hide yes)
			(effects
				(font
					(size 1.016 1.016)
					(thickness 0.1524)
				)
			)
		)
		(duplicate_pad_numbers_are_jumpers no)
		(fp_line
			(start -0.508 -0.9398)
			(end -0.508 0.9398)
			(stroke
				(width 0.1524)
				(type default)
			)
			(layer "F.SilkS")
		)
		(fp_line
			(start 0.508 -0.9398)
			(end -0.508 -0.9398)
			(stroke
				(width 0.1524)
				(type default)
			)
			(layer "F.SilkS")
		)
		(fp_rect
			(start -0.508 0.9398)
			(end 0.508 -0.9398)
			(stroke
				(width 0)
				(type default)
			)
			(fill no)
			(layer "F.CrtYd")
		)
		(fp_rect
			(start -0.508 0.9398)
			(end 0.508 -0.9398)
			(stroke
				(width 0)
				(type default)
			)
			(fill no)
			(layer "F.Fab")
		)
		(pad "1" smd custom
			(at 0 -0.4445 270)
			(size 0.1397 0.1397)
			(layers "F.Cu" "F.Mask" "F.Paste")
			(net "P3V3")
			(options
				(clearance outline)
				(anchor circle)
			)
			(primitives
				(gr_poly
					(pts
						(arc
							(start -0.1778 -0.2794)
							(mid -0.249642 -0.249642)
							(end -0.2794 -0.1778)
						)
						(arc
							(start -0.2794 0.1778)
							(mid -0.249642 0.249642)
							(end -0.1778 0.2794)
						)
						(arc
							(start 0.1778 0.2794)
							(mid 0.249642 0.249642)
							(end 0.2794 0.1778)
						)
						(arc
							(start 0.2794 -0.1778)
							(mid 0.249642 -0.249642)
							(end 0.1778 -0.2794)
						)
					)
					(width 0)
					(fill yes)
				)
			)
		)
		(pad "2" smd custom
			(at 0 0.4445 270)
			(size 0.1397 0.1397)
			(layers "F.Cu" "F.Mask" "F.Paste")
			(net "ATTN_LED_DR10_MOS_N")
			(options
				(clearance outline)
				(anchor circle)
			)
			(primitives
				(gr_poly
					(pts
						(arc
							(start -0.1778 -0.2794)
							(mid -0.249642 -0.249642)
							(end -0.2794 -0.1778)
						)
						(arc
							(start -0.2794 0.1778)
							(mid -0.249642 0.249642)
							(end -0.1778 0.2794)
						)
						(arc
							(start 0.1778 0.2794)
							(mid 0.249642 0.249642)
							(end 0.2794 0.1778)
						)
						(arc
							(start 0.2794 -0.1778)
							(mid 0.249642 -0.249642)
							(end 0.1778 -0.2794)
						)
					)
					(width 0)
					(fill yes)
				)
			)
		)
	)
	(footprint ""
		(layer "F.Cu")
		(at 231.267 -439.293)
		(property "Reference" "R9756"
			(at 0 0 0)
			(layer "F.SilkS")
			(hide yes)
			(effects
				(font
					(size 1.27 1.27)
				)
			)
		)
		(property "Value" "4K7R2F-GP"
			(at 0.064008 -3.993896 0)
			(unlocked yes)
			(layer "F.Fab")
			(hide yes)
			(effects
				(font
					(size 1.016 1.016)
					(thickness 0.1524)
				)
			)
		)
		(property "Device Type" "R402H16"
			(at 0.064008 -5.517896 0)
			(unlocked yes)
			(layer "F.Fab")
			(hide yes)
			(effects
				(font
					(size 1.016 1.016)
					(thickness 0.1524)
				)
			)
		)
		(duplicate_pad_numbers_are_jumpers no)
		(fp_line
			(start -0.508 -0.9398)
			(end -0.508 0.9398)
			(stroke
				(width 0.1524)
				(type default)
			)
			(layer "F.SilkS")
		)
		(fp_line
			(start 0.508 -0.9398)
			(end -0.508 -0.9398)
			(stroke
				(width 0.1524)
				(type default)
			)
			(layer "F.SilkS")
		)
		(fp_rect
			(start -0.508 0.9398)
			(end 0.508 -0.9398)
			(stroke
				(width 0)
				(type default)
			)
			(fill no)
			(layer "F.CrtYd")
		)
		(fp_rect
			(start -0.508 0.9398)
			(end 0.508 -0.9398)
			(stroke
				(width 0)
				(type default)
			)
			(fill no)
			(layer "F.Fab")
		)
		(pad "1" smd custom
			(at 0 -0.4445)
			(size 0.1397 0.1397)
			(layers "F.Cu" "F.Mask" "F.Paste")
			(net "P3V3")
			(options
				(clearance outline)
				(anchor circle)
			)
			(primitives
				(gr_poly
					(pts
						(arc
							(start -0.1778 -0.2794)
							(mid -0.249642 -0.249642)
							(end -0.2794 -0.1778)
						)
						(arc
							(start -0.2794 0.1778)
							(mid -0.249642 0.249642)
							(end -0.1778 0.2794)
						)
						(arc
							(start 0.1778 0.2794)
							(mid 0.249642 0.249642)
							(end 0.2794 0.1778)
						)
						(arc
							(start 0.2794 -0.1778)
							(mid 0.249642 -0.249642)
							(end 0.1778 -0.2794)
						)
					)
					(width 0)
					(fill yes)
				)
			)
		)
		(pad "2" smd custom
			(at 0 0.4445)
			(size 0.1397 0.1397)
			(layers "F.Cu" "F.Mask" "F.Paste")
			(net "TPS53312_P3V3_PG")
			(options
				(clearance outline)
				(anchor circle)
			)
			(primitives
				(gr_poly
					(pts
						(arc
							(start -0.1778 -0.2794)
							(mid -0.249642 -0.249642)
							(end -0.2794 -0.1778)
						)
						(arc
							(start -0.2794 0.1778)
							(mid -0.249642 0.249642)
							(end -0.1778 0.2794)
						)
						(arc
							(start 0.1778 0.2794)
							(mid 0.249642 0.249642)
							(end 0.2794 0.1778)
						)
						(arc
							(start 0.2794 -0.1778)
							(mid 0.249642 -0.249642)
							(end 0.1778 -0.2794)
						)
					)
					(width 0)
					(fill yes)
				)
			)
		)
	)
)
